(kicad_pcb
	(version 20260206)
	(generator "pcbnew")
	(generator_version "10.0")
	(general
		(thickness 1.6)
		(legacy_teardrops no)
	)
	(paper "A4")
	(title_block
		(title "Bryce Canyon_R.DPB_16317-1_OCP.brd")
		(comment 1 "Bryce Canyon / footprints 693-697 of 2099")
	)
	(layers
		(0 "F.Cu" signal "TOP")
		(4 "In1.Cu" signal "L2GND")
		(6 "In2.Cu" signal "L3")
		(8 "In3.Cu" signal "L4VCC")
		(10 "In4.Cu" signal "L5VCC")
		(12 "In5.Cu" signal "L6")
		(14 "In6.Cu" signal "L7GND")
		(2 "B.Cu" signal "BOTTOM")
		(9 "F.Adhes" user "F.Adhesive")
		(11 "B.Adhes" user "B.Adhesive")
		(13 "F.Paste" user "Package Geometry/Pastemask Top")
		(15 "B.Paste" user "Package Geometry/Pastemask Bottom")
		(5 "F.SilkS" user "Ref Des/Silkscreen Top")
		(7 "B.SilkS" user "Ref Des/Silkscreen Bottom")
		(1 "F.Mask" user "Board Geometry/Soldermask Top")
		(3 "B.Mask" user "Board Geometry/Soldermask Bottom")
		(17 "Dwgs.User" user "User.Drawings")
		(19 "Cmts.User" user "User.Comments")
		(21 "Eco1.User" user "User.Eco1")
		(23 "Eco2.User" user "User.Eco2")
		(25 "Edge.Cuts" user "Board Geometry/Outline")
		(27 "Margin" user)
		(31 "F.CrtYd" user "Package Geometry/Place Bound Top")
		(29 "B.CrtYd" user "Package Geometry/Place Bound Bottom")
		(35 "F.Fab" user "Ref Des/Assembly Top")
		(33 "B.Fab" user "Ref Des/Assembly Bottom")
	)
	(footprint ""
		(layer "F.Cu")
		(at 174.371 -374.904 90)
		(property "Reference" "R1001"
			(at 0 0 90)
			(layer "F.SilkS")
			(hide yes)
			(effects
				(font
					(size 1.27 1.27)
				)
			)
		)
		(property "Value" "11KR2F-L-GP"
			(at 0.064008 -3.993896 90)
			(unlocked yes)
			(layer "F.Fab")
			(hide yes)
			(effects
				(font
					(size 1.016 1.016)
					(thickness 0.1524)
				)
			)
		)
		(property "Device Type" "R402H16"
			(at 0.064008 -5.517896 90)
			(unlocked yes)
			(layer "F.Fab")
			(hide yes)
			(effects
				(font
					(size 1.016 1.016)
					(thickness 0.1524)
				)
			)
		)
		(duplicate_pad_numbers_are_jumpers no)
		(fp_line
			(start 0.508 -0.9398)
			(end -0.508 -0.9398)
			(stroke
				(width 0.1524)
				(type default)
			)
			(layer "F.SilkS")
		)
		(fp_line
			(start -0.508 -0.9398)
			(end -0.508 0.9398)
			(stroke
				(width 0.1524)
				(type default)
			)
			(layer "F.SilkS")
		)
		(fp_rect
			(start -0.508 0.9398)
			(end 0.508 -0.9398)
			(stroke
				(width 0)
				(type default)
			)
			(fill no)
			(layer "F.CrtYd")
		)
		(fp_rect
			(start -0.508 0.9398)
			(end 0.508 -0.9398)
			(stroke
				(width 0)
				(type default)
			)
			(fill no)
			(layer "F.Fab")
		)
		(pad "1" smd custom
			(at 0 -0.4445 90)
			(size 0.1397 0.1397)
			(layers "F.Cu" "F.Mask" "F.Paste")
			(net "MB0_P12V_PWGIN_R")
			(options
				(clearance outline)
				(anchor circle)
			)
			(primitives
				(gr_poly
					(pts
						(arc
							(start -0.1778 -0.2794)
							(mid -0.249642 -0.249642)
							(end -0.2794 -0.1778)
						)
						(arc
							(start -0.2794 0.1778)
							(mid -0.249642 0.249642)
							(end -0.1778 0.2794)
						)
						(arc
							(start 0.1778 0.2794)
							(mid 0.249642 0.249642)
							(end 0.2794 0.1778)
						)
						(arc
							(start 0.2794 -0.1778)
							(mid 0.249642 -0.249642)
							(end 0.1778 -0.2794)
						)
					)
					(width 0)
					(fill yes)
				)
			)
		)
		(pad "2" smd custom
			(at 0 0.4445 90)
			(size 0.1397 0.1397)
			(layers "F.Cu" "F.Mask" "F.Paste")
			(net "AGND_CURRENT_MON")
			(options
				(clearance outline)
				(anchor circle)
			)
			(primitives
				(gr_poly
					(pts
						(arc
							(start -0.1778 -0.2794)
							(mid -0.249642 -0.249642)
							(end -0.2794 -0.1778)
						)
						(arc
							(start -0.2794 0.1778)
							(mid -0.249642 0.249642)
							(end -0.1778 0.2794)
						)
						(arc
							(start 0.1778 0.2794)
							(mid 0.249642 0.249642)
							(end 0.2794 0.1778)
						)
						(arc
							(start 0.2794 -0.1778)
							(mid 0.249642 -0.249642)
							(end 0.1778 -0.2794)
						)
					)
					(width 0)
					(fill yes)
				)
			)
		)
	)
	(footprint ""
		(layer "F.Cu")
		(at 459.359 -15.9258)
		(property "Reference" "R864"
			(at 0 0 0)
			(layer "F.SilkS")
			(hide yes)
			(effects
				(font
					(size 1.27 1.27)
				)
			)
		)
		(property "Value" "4K7R2F-GP"
			(at 0.064008 -3.993896 0)
			(unlocked yes)
			(layer "F.Fab")
			(hide yes)
			(effects
				(font
					(size 1.016 1.016)
					(thickness 0.1524)
				)
			)
		)
		(property "Device Type" "R402H16"
			(at 0.064008 -5.517896 0)
			(unlocked yes)
			(layer "F.Fab")
			(hide yes)
			(effects
				(font
					(size 1.016 1.016)
					(thickness 0.1524)
				)
			)
		)
		(duplicate_pad_numbers_are_jumpers no)
		(fp_line
			(start -0.508 -0.9398)
			(end -0.508 0.9398)
			(stroke
				(width 0.1524)
				(type default)
			)
			(layer "F.SilkS")
		)
		(fp_line
			(start 0.508 -0.9398)
			(end -0.508 -0.9398)
			(stroke
				(width 0.1524)
				(type default)
			)
			(layer "F.SilkS")
		)
		(fp_rect
			(start -0.508 0.9398)
			(end 0.508 -0.9398)
			(stroke
				(width 0)
				(type default)
			)
			(fill no)
			(layer "F.CrtYd")
		)
		(fp_rect
			(start -0.508 0.9398)
			(end 0.508 -0.9398)
			(stroke
				(width 0)
				(type default)
			)
			(fill no)
			(layer "F.Fab")
		)
		(pad "1" smd custom
			(at 0 -0.4445)
			(size 0.1397 0.1397)
			(layers "F.Cu" "F.Mask" "F.Paste")
			(net "SW_PWR_R_HDD34")
			(options
				(clearance outline)
				(anchor circle)
			)
			(primitives
				(gr_poly
					(pts
						(arc
							(start -0.1778 -0.2794)
							(mid -0.249642 -0.249642)
							(end -0.2794 -0.1778)
						)
						(arc
							(start -0.2794 0.1778)
							(mid -0.249642 0.249642)
							(end -0.1778 0.2794)
						)
						(arc
							(start 0.1778 0.2794)
							(mid 0.249642 0.249642)
							(end 0.2794 0.1778)
						)
						(arc
							(start 0.2794 -0.1778)
							(mid 0.249642 -0.249642)
							(end 0.1778 -0.2794)
						)
					)
					(width 0)
					(fill yes)
				)
			)
		)
		(pad "2" smd custom
			(at 0 0.4445)
			(size 0.1397 0.1397)
			(layers "F.Cu" "F.Mask" "F.Paste")
			(net "GND")
			(options
				(clearance outline)
				(anchor circle)
			)
			(primitives
				(gr_poly
					(pts
						(arc
							(start -0.1778 -0.2794)
							(mid -0.249642 -0.249642)
							(end -0.2794 -0.1778)
						)
						(arc
							(start -0.2794 0.1778)
							(mid -0.249642 0.249642)
							(end -0.1778 0.2794)
						)
						(arc
							(start 0.1778 0.2794)
							(mid 0.249642 0.249642)
							(end 0.2794 0.1778)
						)
						(arc
							(start 0.2794 -0.1778)
							(mid 0.249642 -0.249642)
							(end 0.1778 -0.2794)
						)
					)
					(width 0)
					(fill yes)
				)
			)
		)
	)
	(footprint ""
		(layer "F.Cu")
		(at 447.04 -151.13 -90)
		(property "Reference" "R580"
			(at 0 0 270)
			(layer "F.SilkS")
			(hide yes)
			(effects
				(font
					(size 1.27 1.27)
				)
			)
		)
		(property "Value" "220R3F-1-GP"
			(at -0.0254 -2.5146 270)
			(unlocked yes)
			(layer "F.Fab")
			(hide yes)
			(effects
				(font
					(size 1.016 1.016)
					(thickness 0.1524)
				)
			)
		)
		(property "Device Type" "R603H22"
			(at -0.0254 -4.0386 270)
			(unlocked yes)
			(layer "F.Fab")
			(hide yes)
			(effects
				(font
					(size 1.016 1.016)
					(thickness 0.1524)
				)
			)
		)
		(duplicate_pad_numbers_are_jumpers no)
		(fp_line
			(start -0.4826 0)
			(end -0.2032 0)
			(stroke
				(width 0.2032)
				(type default)
			)
			(layer "F.SilkS")
		)
		(fp_line
			(start 0.2032 0)
			(end 0.4826 0)
			(stroke
				(width 0.2032)
				(type default)
			)
			(layer "F.SilkS")
		)
		(fp_rect
			(start -0.5842 1.3335)
			(end 0.5842 -1.3335)
			(stroke
				(width 0)
				(type default)
			)
			(fill no)
			(layer "F.CrtYd")
		)
		(fp_rect
			(start -0.5842 1.3335)
			(end 0.5842 -1.3335)
			(stroke
				(width 0)
				(type default)
			)
			(fill no)
			(layer "F.Fab")
		)
		(pad "1" smd custom
			(at 0 -0.762 270)
			(size 0.2159 0.2159)
			(layers "F.Cu" "F.Mask" "F.Paste")
			(net "HDD_PRSNT_22")
			(options
				(clearance outline)
				(anchor circle)
			)
			(primitives
				(gr_poly
					(pts
						(arc
							(start -0.3302 -0.4318)
							(mid -0.402042 -0.402042)
							(end -0.4318 -0.3302)
						)
						(arc
							(start -0.4318 0.3302)
							(mid -0.402042 0.402042)
							(end -0.3302 0.4318)
						)
						(arc
							(start 0.3302 0.4318)
							(mid 0.402042 0.402042)
							(end 0.4318 0.3302)
						)
						(arc
							(start 0.4318 -0.3302)
							(mid 0.402042 -0.402042)
							(end 0.3302 -0.4318)
						)
					)
					(width 0)
					(fill yes)
				)
			)
		)
		(pad "2" smd custom
			(at 0 0.762 270)
			(size 0.2159 0.2159)
			(layers "F.Cu" "F.Mask" "F.Paste")
			(net "DRIVE_B_22_INS")
			(options
				(clearance outline)
				(anchor circle)
			)
			(primitives
				(gr_poly
					(pts
						(arc
							(start -0.3302 -0.4318)
							(mid -0.402042 -0.402042)
							(end -0.4318 -0.3302)
						)
						(arc
							(start -0.4318 0.3302)
							(mid -0.402042 0.402042)
							(end -0.3302 0.4318)
						)
						(arc
							(start 0.3302 0.4318)
							(mid 0.402042 0.402042)
							(end 0.4318 0.3302)
						)
						(arc
							(start 0.4318 -0.3302)
							(mid 0.402042 -0.402042)
							(end 0.3302 -0.4318)
						)
					)
					(width 0)
					(fill yes)
				)
			)
		)
	)
	(footprint ""
		(layer "F.Cu")
		(at 209.423 -205.994 -90)
		(property "Reference" "R49"
			(at 0 0 270)
			(layer "F.SilkS")
			(hide yes)
			(effects
				(font
					(size 1.27 1.27)
				)
			)
		)
		(property "Value" "0R2J-2-GP"
			(at 0.064008 -3.993896 270)
			(unlocked yes)
			(layer "F.Fab")
			(hide yes)
			(effects
				(font
					(size 1.016 1.016)
					(thickness 0.1524)
				)
			)
		)
		(property "Device Type" "R402H16"
			(at 0.064008 -5.517896 270)
			(unlocked yes)
			(layer "F.Fab")
			(hide yes)
			(effects
				(font
					(size 1.016 1.016)
					(thickness 0.1524)
				)
			)
		)
		(duplicate_pad_numbers_are_jumpers no)
		(fp_line
			(start -0.508 -0.9398)
			(end -0.508 0.9398)
			(stroke
				(width 0.1524)
				(type default)
			)
			(layer "F.SilkS")
		)
		(fp_line
			(start 0.508 -0.9398)
			(end -0.508 -0.9398)
			(stroke
				(width 0.1524)
				(type default)
			)
			(layer "F.SilkS")
		)
		(fp_rect
			(start -0.508 0.9398)
			(end 0.508 -0.9398)
			(stroke
				(width 0)
				(type default)
			)
			(fill no)
			(layer "F.CrtYd")
		)
		(fp_rect
			(start -0.508 0.9398)
			(end 0.508 -0.9398)
			(stroke
				(width 0)
				(type default)
			)
			(fill no)
			(layer "F.Fab")
		)
		(pad "1" smd custom
			(at 0 -0.4445 270)
			(size 0.1397 0.1397)
			(layers "F.Cu" "F.Mask" "F.Paste")
			(net "IO_EXP5_SCL")
			(options
				(clearance outline)
				(anchor circle)
			)
			(primitives
				(gr_poly
					(pts
						(arc
							(start -0.1778 -0.2794)
							(mid -0.249642 -0.249642)
							(end -0.2794 -0.1778)
						)
						(arc
							(start -0.2794 0.1778)
							(mid -0.249642 0.249642)
							(end -0.1778 0.2794)
						)
						(arc
							(start 0.1778 0.2794)
							(mid 0.249642 0.249642)
							(end 0.2794 0.1778)
						)
						(arc
							(start 0.2794 -0.1778)
							(mid 0.249642 -0.249642)
							(end 0.1778 -0.2794)
						)
					)
					(width 0)
					(fill yes)
				)
			)
		)
		(pad "2" smd custom
			(at 0 0.4445 270)
			(size 0.1397 0.1397)
			(layers "F.Cu" "F.Mask" "F.Paste")
			(net "I2C_DRIVE_B_INS_SCL")
			(options
				(clearance outline)
				(anchor circle)
			)
			(primitives
				(gr_poly
					(pts
						(arc
							(start -0.1778 -0.2794)
							(mid -0.249642 -0.249642)
							(end -0.2794 -0.1778)
						)
						(arc
							(start -0.2794 0.1778)
							(mid -0.249642 0.249642)
							(end -0.1778 0.2794)
						)
						(arc
							(start 0.1778 0.2794)
							(mid 0.249642 0.249642)
							(end 0.2794 0.1778)
						)
						(arc
							(start 0.2794 -0.1778)
							(mid 0.249642 -0.249642)
							(end 0.1778 -0.2794)
						)
					)
					(width 0)
					(fill yes)
				)
			)
		)
	)
	(footprint ""
		(layer "F.Cu")
		(at 307.300884 -358.470962 180)
		(property "Reference" "Q267"
			(at 0 0 180)
			(layer "F.SilkS")
			(hide yes)
			(effects
				(font
					(size 1.27 1.27)
				)
			)
		)
		(property "Value" "2N7002K-2-GP"
			(at 0.127 -8.9662 180)
			(unlocked yes)
			(layer "F.Fab")
			(hide yes)
			(effects
				(font
					(size 1.016 1.016)
					(thickness 0.1524)
				)
			)
		)
		(property "Device Type" "SOT23DGS2D4H44"
			(at 0.127 -10.4902 180)
			(unlocked yes)
			(layer "F.Fab")
			(hide yes)
			(effects
				(font
					(size 1.016 1.016)
					(thickness 0.1524)
				)
			)
		)
		(duplicate_pad_numbers_are_jumpers no)
		(fp_line
			(start 1.651 1.778)
			(end 1.651 -1.778)
			(stroke
				(width 0.1524)
				(type default)
			)
			(layer "F.SilkS")
		)
		(fp_line
			(start 1.651 -1.778)
			(end -1.651 -1.778)
			(stroke
				(width 0.1524)
				(type default)
			)
			(layer "F.SilkS")
		)
		(fp_line
			(start -1.651 1.778)
			(end 1.651 1.778)
			(stroke
				(width 0.1524)
				(type default)
			)
			(layer "F.SilkS")
		)
		(fp_line
			(start -1.651 -1.778)
			(end -1.651 1.778)
			(stroke
				(width 0.1524)
				(type default)
			)
			(layer "F.SilkS")
		)
		(fp_poly
			(pts
				(xy -1.778 1.8796) (xy -1.778 -1.8796) (xy 1.778 -1.8796) (xy 1.778 1.8796)
			)
			(stroke
				(width 0)
				(type default)
			)
			(fill no)
			(layer "F.CrtYd")
		)
		(fp_poly
			(pts
				(xy -1.778 1.8796) (xy -1.778 -1.8796) (xy 1.778 -1.8796) (xy 1.778 1.8796)
			)
			(stroke
				(width 0)
				(type default)
			)
			(fill no)
			(layer "F.Fab")
		)
		(pad "D" smd custom
			(at 0 -0.9525 180)
			(size 0.1905 0.1905)
			(layers "F.Cu" "F.Mask" "F.Paste")
			(net "FANTACH_B_OE_N")
			(options
				(clearance outline)
				(anchor circle)
			)
			(primitives
				(gr_poly
					(pts
						(arc
							(start -0.1778 0.5715)
							(mid -0.321484 0.511984)
							(end -0.381 0.3683)
						)
						(arc
							(start -0.381 -0.3683)
							(mid -0.321484 -0.511984)
							(end -0.1778 -0.5715)
						)
						(arc
							(start 0.1778 -0.5715)
							(mid 0.321484 -0.511984)
							(end 0.381 -0.3683)
						)
						(arc
							(start 0.381 0.3683)
							(mid 0.321484 0.511984)
							(end 0.1778 0.5715)
						)
					)
					(width 0)
					(fill yes)
				)
			)
		)
		(pad "G" smd custom
			(at -0.98425 0.9525 180)
			(size 0.1905 0.1905)
			(layers "F.Cu" "F.Mask" "F.Paste")
			(net "FANTACH_B_OE")
			(options
				(clearance outline)
				(anchor circle)
			)
			(primitives
				(gr_poly
					(pts
						(arc
							(start -0.1778 0.5715)
							(mid -0.321484 0.511984)
							(end -0.381 0.3683)
						)
						(arc
							(start -0.381 -0.3683)
							(mid -0.321484 -0.511984)
							(end -0.1778 -0.5715)
						)
						(arc
							(start 0.1778 -0.5715)
							(mid 0.321484 -0.511984)
							(end 0.381 -0.3683)
						)
						(arc
							(start 0.381 0.3683)
							(mid 0.321484 0.511984)
							(end 0.1778 0.5715)
						)
					)
					(width 0)
					(fill yes)
				)
			)
		)
		(pad "S" smd custom
			(at 0.98425 0.9525 180)
			(size 0.1905 0.1905)
			(layers "F.Cu" "F.Mask" "F.Paste")
			(net "GND")
			(options
				(clearance outline)
				(anchor circle)
			)
			(primitives
				(gr_poly
					(pts
						(arc
							(start -0.1778 0.5715)
							(mid -0.321484 0.511984)
							(end -0.381 0.3683)
						)
						(arc
							(start -0.381 -0.3683)
							(mid -0.321484 -0.511984)
							(end -0.1778 -0.5715)
						)
						(arc
							(start 0.1778 -0.5715)
							(mid 0.321484 -0.511984)
							(end 0.381 -0.3683)
						)
						(arc
							(start 0.381 0.3683)
							(mid 0.321484 0.511984)
							(end 0.1778 0.5715)
						)
					)
					(width 0)
					(fill yes)
				)
			)
		)
	)
)
